(kicad_pcb
	(version 20260206)
	(generator "pcbnew")
	(generator_version "10.0")
	(general
		(thickness 1.6)
		(legacy_teardrops no)
	)
	(paper "A4")
	(title_block
		(title "01162023_DA0F0TEBIF0_F0T_Expander_BD_F_brd_V02_OCP.brd")
		(comment 1 "Grand Teton / footprints 3443-3449 of 9728")
	)
	(layers
		(0 "F.Cu" signal "TOP")
		(4 "In1.Cu" signal "GND")
		(6 "In2.Cu" signal "VCC")
		(8 "In3.Cu" signal "VCC1")
		(10 "In4.Cu" signal "GND1")
		(12 "In5.Cu" signal "IN1")
		(14 "In6.Cu" signal "GND2")
		(16 "In7.Cu" signal "IN2")
		(18 "In8.Cu" signal "GND3")
		(20 "In9.Cu" signal "IN3")
		(22 "In10.Cu" signal "GND4")
		(24 "In11.Cu" signal "IN4")
		(26 "In12.Cu" signal "GND5")
		(28 "In13.Cu" signal "IN5")
		(30 "In14.Cu" signal "GND6")
		(32 "In15.Cu" signal "IN6")
		(34 "In16.Cu" signal "GND7")
		(2 "B.Cu" signal "BOTTOM")
		(9 "F.Adhes" user "F.Adhesive")
		(11 "B.Adhes" user "B.Adhesive")
		(13 "F.Paste" user "Package Geometry/Pastemask Top")
		(15 "B.Paste" user "Package Geometry/Pastemask Bottom")
		(5 "F.SilkS" user "Ref Des/Silkscreen Top")
		(7 "B.SilkS" user "Ref Des/Silkscreen Bottom")
		(1 "F.Mask" user "Board Geometry/Soldermask Top")
		(3 "B.Mask" user "Board Geometry/Soldermask Bottom")
		(17 "Dwgs.User" user "User.Drawings")
		(19 "Cmts.User" user "User.Comments")
		(21 "Eco1.User" user "User.Eco1")
		(23 "Eco2.User" user "User.Eco2")
		(25 "Edge.Cuts" user "Board Geometry/Outline")
		(27 "Margin" user)
		(31 "F.CrtYd" user "Package Geometry/Place Bound Top")
		(29 "B.CrtYd" user "Package Geometry/Place Bound Bottom")
		(35 "F.Fab" user "Ref Des/Assembly Top")
		(33 "B.Fab" user "Ref Des/Assembly Bottom")
	)
	(footprint ""
		(layer "F.Cu")
		(at 383.159 -212.344)
		(property "Reference" "R4622"
			(at 0 0 0)
			(layer "F.SilkS")
			(hide yes)
			(effects
				(font
					(size 1.27 1.27)
				)
			)
		)
		(property "Value" ""
			(at 0 0 0)
			(layer "F.Fab")
			(effects
				(font
					(size 1.27 1.27)
				)
			)
		)
		(duplicate_pad_numbers_are_jumpers no)
		(fp_line
			(start -0.7874 -0.4064)
			(end 0.7874 -0.4064)
			(stroke
				(width 0.1524)
				(type default)
			)
			(layer "F.SilkS")
		)
		(fp_line
			(start -0.7874 0.4064)
			(end -0.7874 -0.4064)
			(stroke
				(width 0.1524)
				(type default)
			)
			(layer "F.SilkS")
		)
		(fp_line
			(start 0.7874 -0.4064)
			(end 0.7874 0.4064)
			(stroke
				(width 0.1524)
				(type default)
			)
			(layer "F.SilkS")
		)
		(fp_line
			(start 0.7874 0.4064)
			(end -0.7874 0.4064)
			(stroke
				(width 0.1524)
				(type default)
			)
			(layer "F.SilkS")
		)
		(fp_line
			(start -0.67945 -0.305054)
			(end -0.12065 -0.305054)
			(stroke
				(width 0.1)
				(type default)
			)
			(layer "F.Fab")
		)
		(fp_line
			(start -0.67945 0.3048)
			(end -0.67945 -0.305054)
			(stroke
				(width 0.1)
				(type default)
			)
			(layer "F.Fab")
		)
		(fp_line
			(start -0.12065 -0.305054)
			(end -0.12065 -0.2794)
			(stroke
				(width 0.1)
				(type default)
			)
			(layer "F.Fab")
		)
		(fp_line
			(start -0.12065 -0.2794)
			(end 0.12065 -0.2794)
			(stroke
				(width 0.1)
				(type default)
			)
			(layer "F.Fab")
		)
		(fp_line
			(start -0.12065 0.2794)
			(end -0.12065 0.3048)
			(stroke
				(width 0.1)
				(type default)
			)
			(layer "F.Fab")
		)
		(fp_line
			(start -0.12065 0.3048)
			(end -0.67945 0.3048)
			(stroke
				(width 0.1)
				(type default)
			)
			(layer "F.Fab")
		)
		(fp_line
			(start 0.120396 0.2794)
			(end -0.12065 0.2794)
			(stroke
				(width 0.1)
				(type default)
			)
			(layer "F.Fab")
		)
		(fp_line
			(start 0.120396 0.3048)
			(end 0.120396 0.2794)
			(stroke
				(width 0.1)
				(type default)
			)
			(layer "F.Fab")
		)
		(fp_line
			(start 0.12065 -0.3048)
			(end 0.67945 -0.3048)
			(stroke
				(width 0.1)
				(type default)
			)
			(layer "F.Fab")
		)
		(fp_line
			(start 0.12065 -0.2794)
			(end 0.12065 -0.3048)
			(stroke
				(width 0.1)
				(type default)
			)
			(layer "F.Fab")
		)
		(fp_line
			(start 0.67945 -0.3048)
			(end 0.67945 0.3048)
			(stroke
				(width 0.1)
				(type default)
			)
			(layer "F.Fab")
		)
		(fp_line
			(start 0.67945 0.3048)
			(end 0.120396 0.3048)
			(stroke
				(width 0.1)
				(type default)
			)
			(layer "F.Fab")
		)
		(pad "1" smd circle
			(at -0.40005 0)
			(size 0 0)
			(layers "F.Cu" "F.Mask" "F.Paste")
			(net "PCA9555_0_PEX0_A0")
		)
		(pad "2" smd circle
			(at 0.40005 0)
			(size 0 0)
			(layers "F.Cu" "F.Mask" "F.Paste")
			(net "P3V3_AUX")
		)
	)
	(footprint ""
		(layer "F.Cu")
		(at 224.993454 -117.265196 -90)
		(property "Reference" "PD18"
			(at 4.031996 -2.236216 90)
			(unlocked yes)
			(layer "F.SilkS")
			(effects
				(font
					(size 0.7874 0.5842)
					(thickness 0.1524)
				)
				(justify left)
			)
		)
		(property "Value" ""
			(at 0 0 270)
			(layer "F.Fab")
			(effects
				(font
					(size 1.27 1.27)
				)
			)
		)
		(duplicate_pad_numbers_are_jumpers no)
		(fp_line
			(start -3.400044 1.459992)
			(end -3.400044 -1.459992)
			(stroke
				(width 0.1524)
				(type default)
			)
			(layer "F.SilkS")
		)
		(fp_line
			(start 4.107942 1.459992)
			(end -3.400044 1.459992)
			(stroke
				(width 0.1524)
				(type default)
			)
			(layer "F.SilkS")
		)
		(fp_line
			(start -3.400044 -1.459992)
			(end 4.107942 -1.459992)
			(stroke
				(width 0.1524)
				(type default)
			)
			(layer "F.SilkS")
		)
		(fp_line
			(start 4.107942 -1.459992)
			(end 4.107942 1.459992)
			(stroke
				(width 0.1524)
				(type default)
			)
			(layer "F.SilkS")
		)
		(fp_poly
			(pts
				(xy 4.107942 -1.459992) (xy 4.107942 1.459992) (xy 3.308096 1.459992) (xy 3.308096 -1.459992)
			)
			(stroke
				(width 0)
				(type default)
			)
			(fill yes)
			(layer "F.SilkS")
		)
		(fp_line
			(start -2.29997 1.459992)
			(end -2.29997 -1.459992)
			(stroke
				(width 0.1)
				(type default)
			)
			(layer "F.Fab")
		)
		(fp_line
			(start 2.29997 1.459992)
			(end -2.29997 1.459992)
			(stroke
				(width 0.1)
				(type default)
			)
			(layer "F.Fab")
		)
		(fp_line
			(start -2.29997 -1.459992)
			(end 2.29997 -1.459992)
			(stroke
				(width 0.1)
				(type default)
			)
			(layer "F.Fab")
		)
		(fp_line
			(start 2.29997 -1.459992)
			(end 2.29997 1.459992)
			(stroke
				(width 0.1)
				(type default)
			)
			(layer "F.Fab")
		)
		(fp_text user "-"
			(at 5.4102 0.29845 90)
			(unlocked yes)
			(layer "F.SilkS")
			(effects
				(font
					(size 1.905 1.4224)
					(thickness 0.1524)
				)
				(justify left)
			)
		)
		(fp_text user "+"
			(at -4.7752 -0.12065 270)
			(unlocked yes)
			(layer "F.SilkS")
			(effects
				(font
					(size 1.905 1.4224)
					(thickness 0.1524)
				)
				(justify left)
			)
		)
		(fp_text user "-"
			(at 5.4102 0.29845 90)
			(unlocked yes)
			(layer "F.Fab")
			(effects
				(font
					(size 1.905 1.4224)
					(thickness 0.1524)
				)
				(justify left)
			)
		)
		(fp_text user "+"
			(at -4.7752 -0.12065 270)
			(unlocked yes)
			(layer "F.Fab")
			(effects
				(font
					(size 1.905 1.4224)
					(thickness 0.1524)
				)
				(justify left)
			)
		)
		(pad "A" smd rect
			(at -1.999996 0)
			(size 1.7018 2.5146)
			(layers "F.Cu" "F.Mask" "F.Paste")
			(net "GND")
		)
		(pad "C" smd rect
			(at 1.999996 0)
			(size 1.7018 2.5146)
			(layers "F.Cu" "F.Mask" "F.Paste")
			(net "P12V_NIC3_R")
		)
	)
	(footprint ""
		(layer "F.Cu")
		(at 50.396648 -356.244906 90)
		(property "Reference" "C2182"
			(at 0 0 90)
			(layer "F.SilkS")
			(hide yes)
			(effects
				(font
					(size 1.27 1.27)
				)
			)
		)
		(property "Value" ""
			(at 0 0 90)
			(layer "F.Fab")
			(effects
				(font
					(size 1.27 1.27)
				)
			)
		)
		(duplicate_pad_numbers_are_jumpers no)
		(fp_line
			(start 0.299974 -0.150114)
			(end 0.299974 0.150114)
			(stroke
				(width 0.1)
				(type default)
			)
			(layer "F.Fab")
		)
		(fp_line
			(start -0.299974 -0.150114)
			(end 0.299974 -0.150114)
			(stroke
				(width 0.1)
				(type default)
			)
			(layer "F.Fab")
		)
		(fp_line
			(start 0.299974 0.150114)
			(end -0.299974 0.150114)
			(stroke
				(width 0.1)
				(type default)
			)
			(layer "F.Fab")
		)
		(fp_line
			(start -0.299974 0.150114)
			(end -0.299974 -0.150114)
			(stroke
				(width 0.1)
				(type default)
			)
			(layer "F.Fab")
		)
		(pad "1" smd rect
			(at -0.2667 0 90)
			(size 0.3048 0.381)
			(layers "F.Cu" "F.Mask" "F.Paste")
			(net "P5E_PEX0_STN4_TX_DP<64>")
		)
		(pad "2" smd rect
			(at 0.2667 0 90)
			(size 0.3048 0.381)
			(layers "F.Cu" "F.Mask" "F.Paste")
			(net "P5E_PEX0_STN4_TX_C_DP<64>")
		)
	)
	(footprint ""
		(layer "F.Cu")
		(at 12.748768 -162.003994 90)
		(property "Reference" "PR6875"
			(at 0 0 90)
			(layer "F.SilkS")
			(hide yes)
			(effects
				(font
					(size 1.27 1.27)
				)
			)
		)
		(property "Value" ""
			(at 0 0 90)
			(layer "F.Fab")
			(effects
				(font
					(size 1.27 1.27)
				)
			)
		)
		(duplicate_pad_numbers_are_jumpers no)
		(fp_line
			(start 0.7874 -0.4064)
			(end 0.7874 0.4064)
			(stroke
				(width 0.1524)
				(type default)
			)
			(layer "F.SilkS")
		)
		(fp_line
			(start -0.7874 -0.4064)
			(end 0.7874 -0.4064)
			(stroke
				(width 0.1524)
				(type default)
			)
			(layer "F.SilkS")
		)
		(fp_line
			(start 0.7874 0.4064)
			(end -0.7874 0.4064)
			(stroke
				(width 0.1524)
				(type default)
			)
			(layer "F.SilkS")
		)
		(fp_line
			(start -0.7874 0.4064)
			(end -0.7874 -0.4064)
			(stroke
				(width 0.1524)
				(type default)
			)
			(layer "F.SilkS")
		)
		(fp_line
			(start -0.12065 -0.305054)
			(end -0.12065 -0.2794)
			(stroke
				(width 0.1)
				(type default)
			)
			(layer "F.Fab")
		)
		(fp_line
			(start -0.67945 -0.305054)
			(end -0.12065 -0.305054)
			(stroke
				(width 0.1)
				(type default)
			)
			(layer "F.Fab")
		)
		(fp_line
			(start 0.67945 -0.3048)
			(end 0.67945 0.3048)
			(stroke
				(width 0.1)
				(type default)
			)
			(layer "F.Fab")
		)
		(fp_line
			(start 0.12065 -0.3048)
			(end 0.67945 -0.3048)
			(stroke
				(width 0.1)
				(type default)
			)
			(layer "F.Fab")
		)
		(fp_line
			(start 0.12065 -0.2794)
			(end 0.12065 -0.3048)
			(stroke
				(width 0.1)
				(type default)
			)
			(layer "F.Fab")
		)
		(fp_line
			(start -0.12065 -0.2794)
			(end 0.12065 -0.2794)
			(stroke
				(width 0.1)
				(type default)
			)
			(layer "F.Fab")
		)
		(fp_line
			(start 0.120396 0.2794)
			(end -0.12065 0.2794)
			(stroke
				(width 0.1)
				(type default)
			)
			(layer "F.Fab")
		)
		(fp_line
			(start -0.12065 0.2794)
			(end -0.12065 0.3048)
			(stroke
				(width 0.1)
				(type default)
			)
			(layer "F.Fab")
		)
		(fp_line
			(start 0.67945 0.3048)
			(end 0.120396 0.3048)
			(stroke
				(width 0.1)
				(type default)
			)
			(layer "F.Fab")
		)
		(fp_line
			(start 0.120396 0.3048)
			(end 0.120396 0.2794)
			(stroke
				(width 0.1)
				(type default)
			)
			(layer "F.Fab")
		)
		(fp_line
			(start -0.12065 0.3048)
			(end -0.67945 0.3048)
			(stroke
				(width 0.1)
				(type default)
			)
			(layer "F.Fab")
		)
		(fp_line
			(start -0.67945 0.3048)
			(end -0.67945 -0.305054)
			(stroke
				(width 0.1)
				(type default)
			)
			(layer "F.Fab")
		)
		(pad "1" smd circle
			(at -0.40005 0 90)
			(size 0 0)
			(layers "F.Cu" "F.Mask" "F.Paste")
			(net "P12V_NIC0_CO_ISET")
		)
		(pad "2" smd circle
			(at 0.40005 0 90)
			(size 0 0)
			(layers "F.Cu" "F.Mask" "F.Paste")
			(net "GND")
		)
	)
	(footprint ""
		(layer "F.Cu")
		(at 366.092486 -31.825184 180)
		(property "Reference" "C701"
			(at 0 0 180)
			(layer "F.SilkS")
			(hide yes)
			(effects
				(font
					(size 1.27 1.27)
				)
			)
		)
		(property "Value" ""
			(at 0 0 180)
			(layer "F.Fab")
			(effects
				(font
					(size 1.27 1.27)
				)
			)
		)
		(duplicate_pad_numbers_are_jumpers no)
		(fp_line
			(start 0.299974 0.150114)
			(end -0.299974 0.150114)
			(stroke
				(width 0.1)
				(type default)
			)
			(layer "F.Fab")
		)
		(fp_line
			(start 0.299974 -0.150114)
			(end 0.299974 0.150114)
			(stroke
				(width 0.1)
				(type default)
			)
			(layer "F.Fab")
		)
		(fp_line
			(start -0.299974 0.150114)
			(end -0.299974 -0.150114)
			(stroke
				(width 0.1)
				(type default)
			)
			(layer "F.Fab")
		)
		(fp_line
			(start -0.299974 -0.150114)
			(end 0.299974 -0.150114)
			(stroke
				(width 0.1)
				(type default)
			)
			(layer "F.Fab")
		)
		(pad "1" smd rect
			(at -0.2667 0 180)
			(size 0.3048 0.381)
			(layers "F.Cu" "F.Mask" "F.Paste")
			(net "P5E_PEX3_STN2_TX_DN<46>")
		)
		(pad "2" smd rect
			(at 0.2667 0 180)
			(size 0.3048 0.381)
			(layers "F.Cu" "F.Mask" "F.Paste")
			(net "P5E_PEX3_STN2_TX_C_DN<46>")
		)
	)
	(footprint ""
		(layer "F.Cu")
		(at 137.630662 -66.32194 -90)
		(property "Reference" "PC846"
			(at 0 0 270)
			(layer "F.SilkS")
			(hide yes)
			(effects
				(font
					(size 1.27 1.27)
				)
			)
		)
		(property "Value" ""
			(at 0 0 270)
			(layer "F.Fab")
			(effects
				(font
					(size 1.27 1.27)
				)
			)
		)
		(duplicate_pad_numbers_are_jumpers no)
		(fp_line
			(start -0.7874 0.4064)
			(end -0.7874 -0.4064)
			(stroke
				(width 0.1524)
				(type default)
			)
			(layer "F.SilkS")
		)
		(fp_line
			(start 0.7874 0.4064)
			(end -0.7874 0.4064)
			(stroke
				(width 0.1524)
				(type default)
			)
			(layer "F.SilkS")
		)
		(fp_line
			(start -0.7874 -0.4064)
			(end 0.7874 -0.4064)
			(stroke
				(width 0.1524)
				(type default)
			)
			(layer "F.SilkS")
		)
		(fp_line
			(start 0.7874 -0.4064)
			(end 0.7874 0.4064)
			(stroke
				(width 0.1524)
				(type default)
			)
			(layer "F.SilkS")
		)
		(fp_line
			(start -0.67945 0.3048)
			(end -0.67945 -0.305054)
			(stroke
				(width 0.1)
				(type default)
			)
			(layer "F.Fab")
		)
		(fp_line
			(start -0.12065 0.3048)
			(end -0.67945 0.3048)
			(stroke
				(width 0.1)
				(type default)
			)
			(layer "F.Fab")
		)
		(fp_line
			(start 0.120396 0.3048)
			(end 0.120396 0.2794)
			(stroke
				(width 0.1)
				(type default)
			)
			(layer "F.Fab")
		)
		(fp_line
			(start 0.67945 0.3048)
			(end 0.120396 0.3048)
			(stroke
				(width 0.1)
				(type default)
			)
			(layer "F.Fab")
		)
		(fp_line
			(start -0.12065 0.2794)
			(end -0.12065 0.3048)
			(stroke
				(width 0.1)
				(type default)
			)
			(layer "F.Fab")
		)
		(fp_line
			(start 0.120396 0.2794)
			(end -0.12065 0.2794)
			(stroke
				(width 0.1)
				(type default)
			)
			(layer "F.Fab")
		)
		(fp_line
			(start -0.12065 -0.2794)
			(end 0.12065 -0.2794)
			(stroke
				(width 0.1)
				(type default)
			)
			(layer "F.Fab")
		)
		(fp_line
			(start 0.12065 -0.2794)
			(end 0.12065 -0.3048)
			(stroke
				(width 0.1)
				(type default)
			)
			(layer "F.Fab")
		)
		(fp_line
			(start 0.12065 -0.3048)
			(end 0.67945 -0.3048)
			(stroke
				(width 0.1)
				(type default)
			)
			(layer "F.Fab")
		)
		(fp_line
			(start 0.67945 -0.3048)
			(end 0.67945 0.3048)
			(stroke
				(width 0.1)
				(type default)
			)
			(layer "F.Fab")
		)
		(fp_line
			(start -0.67945 -0.305054)
			(end -0.12065 -0.305054)
			(stroke
				(width 0.1)
				(type default)
			)
			(layer "F.Fab")
		)
		(fp_line
			(start -0.12065 -0.305054)
			(end -0.12065 -0.2794)
			(stroke
				(width 0.1)
				(type default)
			)
			(layer "F.Fab")
		)
		(pad "1" smd circle
			(at -0.40005 0 270)
			(size 0 0)
			(layers "F.Cu" "F.Mask" "F.Paste")
			(net "P12V_SSD4_CO_DV_DT")
		)
		(pad "2" smd circle
			(at 0.40005 0 270)
			(size 0 0)
			(layers "F.Cu" "F.Mask" "F.Paste")
			(net "GND")
		)
	)
	(footprint ""
		(layer "F.Cu")
		(at 207.133698 -304.036476 90)
		(property "Reference" "R1317"
			(at 0 0 90)
			(layer "F.SilkS")
			(hide yes)
			(effects
				(font
					(size 1.27 1.27)
				)
			)
		)
		(property "Value" ""
			(at 0 0 90)
			(layer "F.Fab")
			(effects
				(font
					(size 1.27 1.27)
				)
			)
		)
		(duplicate_pad_numbers_are_jumpers no)
		(fp_line
			(start 0.7874 -0.4064)
			(end 0.7874 0.4064)
			(stroke
				(width 0.1524)
				(type default)
			)
			(layer "F.SilkS")
		)
		(fp_line
			(start -0.7874 -0.4064)
			(end 0.7874 -0.4064)
			(stroke
				(width 0.1524)
				(type default)
			)
			(layer "F.SilkS")
		)
		(fp_line
			(start 0.7874 0.4064)
			(end -0.7874 0.4064)
			(stroke
				(width 0.1524)
				(type default)
			)
			(layer "F.SilkS")
		)
		(fp_line
			(start -0.7874 0.4064)
			(end -0.7874 -0.4064)
			(stroke
				(width 0.1524)
				(type default)
			)
			(layer "F.SilkS")
		)
		(fp_line
			(start -0.12065 -0.305054)
			(end -0.12065 -0.2794)
			(stroke
				(width 0.1)
				(type default)
			)
			(layer "F.Fab")
		)
		(fp_line
			(start -0.67945 -0.305054)
			(end -0.12065 -0.305054)
			(stroke
				(width 0.1)
				(type default)
			)
			(layer "F.Fab")
		)
		(fp_line
			(start 0.67945 -0.3048)
			(end 0.67945 0.3048)
			(stroke
				(width 0.1)
				(type default)
			)
			(layer "F.Fab")
		)
		(fp_line
			(start 0.12065 -0.3048)
			(end 0.67945 -0.3048)
			(stroke
				(width 0.1)
				(type default)
			)
			(layer "F.Fab")
		)
		(fp_line
			(start 0.12065 -0.2794)
			(end 0.12065 -0.3048)
			(stroke
				(width 0.1)
				(type default)
			)
			(layer "F.Fab")
		)
		(fp_line
			(start -0.12065 -0.2794)
			(end 0.12065 -0.2794)
			(stroke
				(width 0.1)
				(type default)
			)
			(layer "F.Fab")
		)
		(fp_line
			(start 0.120396 0.2794)
			(end -0.12065 0.2794)
			(stroke
				(width 0.1)
				(type default)
			)
			(layer "F.Fab")
		)
		(fp_line
			(start -0.12065 0.2794)
			(end -0.12065 0.3048)
			(stroke
				(width 0.1)
				(type default)
			)
			(layer "F.Fab")
		)
		(fp_line
			(start 0.67945 0.3048)
			(end 0.120396 0.3048)
			(stroke
				(width 0.1)
				(type default)
			)
			(layer "F.Fab")
		)
		(fp_line
			(start 0.120396 0.3048)
			(end 0.120396 0.2794)
			(stroke
				(width 0.1)
				(type default)
			)
			(layer "F.Fab")
		)
		(fp_line
			(start -0.12065 0.3048)
			(end -0.67945 0.3048)
			(stroke
				(width 0.1)
				(type default)
			)
			(layer "F.Fab")
		)
		(fp_line
			(start -0.67945 0.3048)
			(end -0.67945 -0.305054)
			(stroke
				(width 0.1)
				(type default)
			)
			(layer "F.Fab")
		)
		(pad "1" smd circle
			(at -0.40005 0 90)
			(size 0 0)
			(layers "F.Cu" "F.Mask" "F.Paste")
			(net "GND")
		)
		(pad "2" smd circle
			(at 0.40005 0 90)
			(size 0 0)
			(layers "F.Cu" "F.Mask" "F.Paste")
			(net "PEX1_SPARE1")
		)
	)
)
